# T6G (Grand Teton) — schematic netlist excerpt (pin names and nets, part order shuffled) for the footprints in the layout excerpt that follows; sources: Cadence DE-HDL packaged netlist, KiCad conversion of 04192023_DAF0TMB3IC0_F0TG_MB_C_brd_V02_OCP.brd

R6067  Q_RES  0 5% CHIP  pkg 0402LF  page 151 : A = JTAG_SCM_TDO_R ; B = JTAG_SCM_TDI
C201  Q_CAP  1UF 4V 20% X6S  pkg 0201  page 323 : A = P0V9_CPU1_RT0_2A_2D ; B = GND
C2592  Q_CAP  22UF 4V 20% X6S  pkg C0402  page 70 : A = PVDDCR_SOC_P0 ; B = GND

(kicad_pcb
	(version 20260206)
	(generator "pcbnew")
	(generator_version "10.0")
	(general
		(thickness 1.6)
		(legacy_teardrops no)
	)
	(paper "A4")
	(title_block
		(title "04192023_DAF0TMB3IC0_F0TG_MB_C_brd_V02_OCP.brd")
		(comment 1 "Grand Teton / footprints 6758-6760 of 8354")
	)
	(layers
		(0 "F.Cu" signal "TOP")
		(4 "In1.Cu" signal "GND")
		(6 "In2.Cu" signal "IN1")
		(8 "In3.Cu" signal "GND1")
		(10 "In4.Cu" signal "IN2")
		(12 "In5.Cu" signal "GND2")
		(14 "In6.Cu" signal "IN3")
		(16 "In7.Cu" signal "GND3")
		(18 "In8.Cu" signal "VCC")
		(20 "In9.Cu" signal "VCC1")
		(22 "In10.Cu" signal "GND4")
		(24 "In11.Cu" signal "IN4")
		(26 "In12.Cu" signal "GND5")
		(28 "In13.Cu" signal "IN5")
		(30 "In14.Cu" signal "GND6")
		(32 "In15.Cu" signal "IN6")
		(34 "In16.Cu" signal "GND7")
		(2 "B.Cu" signal "BOTTOM")
		(9 "F.Adhes" user "F.Adhesive")
		(11 "B.Adhes" user "B.Adhesive")
		(13 "F.Paste" user "Package Geometry/Pastemask Top")
		(15 "B.Paste" user "Package Geometry/Pastemask Bottom")
		(5 "F.SilkS" user "Ref Des/Silkscreen Top")
		(7 "B.SilkS" user "Ref Des/Silkscreen Bottom")
		(1 "F.Mask" user "Board Geometry/Soldermask Top")
		(3 "B.Mask" user "Board Geometry/Soldermask Bottom")
		(17 "Dwgs.User" user "User.Drawings")
		(19 "Cmts.User" user "User.Comments")
		(21 "Eco1.User" user "User.Eco1")
		(23 "Eco2.User" user "User.Eco2")
		(25 "Edge.Cuts" user "Board Geometry/Outline")
		(27 "Margin" user)
		(31 "F.CrtYd" user "Package Geometry/Place Bound Top")
		(29 "B.CrtYd" user "Package Geometry/Place Bound Bottom")
		(35 "F.Fab" user "Ref Des/Assembly Top")
		(33 "B.Fab" user "Ref Des/Assembly Bottom")
	)
	(footprint ""
		(layer "B.Cu")
		(at 373.329454 -250.89231)
		(property "Reference" "C2592"
			(at 0 0 0)
			(layer "B.SilkS")
			(hide yes)
			(effects
				(font
					(size 1.27 1.27)
				)
				(justify mirror)
			)
		)
		(property "Value" ""
			(at 0 0 0)
			(layer "B.Fab")
			(effects
				(font
					(size 1.27 1.27)
				)
				(justify mirror)
			)
		)
		(duplicate_pad_numbers_are_jumpers no)
		(fp_line
			(start -0.7874 -0.4064)
			(end -0.7874 0.4064)
			(stroke
				(width 0.1524)
				(type default)
			)
			(layer "B.SilkS")
		)
		(fp_line
			(start -0.7874 0.4064)
			(end 0.7874 0.4064)
			(stroke
				(width 0.1524)
				(type default)
			)
			(layer "B.SilkS")
		)
		(fp_line
			(start 0.7874 -0.4064)
			(end -0.7874 -0.4064)
			(stroke
				(width 0.1524)
				(type default)
			)
			(layer "B.SilkS")
		)
		(fp_line
			(start 0.7874 0.4064)
			(end 0.7874 -0.4064)
			(stroke
				(width 0.1524)
				(type default)
			)
			(layer "B.SilkS")
		)
		(fp_line
			(start -0.67945 -0.3048)
			(end -0.67945 0.3048)
			(stroke
				(width 0.1)
				(type default)
			)
			(layer "B.Fab")
		)
		(fp_line
			(start -0.67945 0.3048)
			(end -0.120396 0.3048)
			(stroke
				(width 0.1)
				(type default)
			)
			(layer "B.Fab")
		)
		(fp_line
			(start -0.12065 -0.3048)
			(end -0.67945 -0.3048)
			(stroke
				(width 0.1)
				(type default)
			)
			(layer "B.Fab")
		)
		(fp_line
			(start -0.12065 -0.2794)
			(end -0.12065 -0.3048)
			(stroke
				(width 0.1)
				(type default)
			)
			(layer "B.Fab")
		)
		(fp_line
			(start -0.120396 0.2794)
			(end 0.12065 0.2794)
			(stroke
				(width 0.1)
				(type default)
			)
			(layer "B.Fab")
		)
		(fp_line
			(start -0.120396 0.3048)
			(end -0.120396 0.2794)
			(stroke
				(width 0.1)
				(type default)
			)
			(layer "B.Fab")
		)
		(fp_line
			(start 0.12065 -0.305054)
			(end 0.12065 -0.2794)
			(stroke
				(width 0.1)
				(type default)
			)
			(layer "B.Fab")
		)
		(fp_line
			(start 0.12065 -0.2794)
			(end -0.12065 -0.2794)
			(stroke
				(width 0.1)
				(type default)
			)
			(layer "B.Fab")
		)
		(fp_line
			(start 0.12065 0.2794)
			(end 0.12065 0.3048)
			(stroke
				(width 0.1)
				(type default)
			)
			(layer "B.Fab")
		)
		(fp_line
			(start 0.12065 0.3048)
			(end 0.67945 0.3048)
			(stroke
				(width 0.1)
				(type default)
			)
			(layer "B.Fab")
		)
		(fp_line
			(start 0.67945 -0.305054)
			(end 0.12065 -0.305054)
			(stroke
				(width 0.1)
				(type default)
			)
			(layer "B.Fab")
		)
		(fp_line
			(start 0.67945 0.3048)
			(end 0.67945 -0.305054)
			(stroke
				(width 0.1)
				(type default)
			)
			(layer "B.Fab")
		)
		(pad "1" smd circle
			(at 0.40005 0 180)
			(size 0 0)
			(layers "B.Cu" "B.Mask" "B.Paste")
			(net "PVDDCR_SOC_P0")
		)
		(pad "2" smd circle
			(at -0.40005 0 180)
			(size 0 0)
			(layers "B.Cu" "B.Mask" "B.Paste")
			(net "GND")
		)
	)
	(footprint ""
		(layer "B.Cu")
		(at 52.178458 -386.766562 90)
		(property "Reference" "C201"
			(at 0 0 90)
			(layer "B.SilkS")
			(hide yes)
			(effects
				(font
					(size 1.27 1.27)
				)
				(justify mirror)
			)
		)
		(property "Value" ""
			(at 0 0 90)
			(layer "B.Fab")
			(effects
				(font
					(size 1.27 1.27)
				)
				(justify mirror)
			)
		)
		(duplicate_pad_numbers_are_jumpers no)
		(fp_line
			(start 0.299974 -0.150114)
			(end -0.299974 -0.150114)
			(stroke
				(width 0.1)
				(type default)
			)
			(layer "B.Fab")
		)
		(fp_line
			(start -0.299974 -0.150114)
			(end -0.299974 0.150114)
			(stroke
				(width 0.1)
				(type default)
			)
			(layer "B.Fab")
		)
		(fp_line
			(start 0.299974 0.150114)
			(end 0.299974 -0.150114)
			(stroke
				(width 0.1)
				(type default)
			)
			(layer "B.Fab")
		)
		(fp_line
			(start -0.299974 0.150114)
			(end 0.299974 0.150114)
			(stroke
				(width 0.1)
				(type default)
			)
			(layer "B.Fab")
		)
		(pad "1" smd rect
			(at 0.2667 0 270)
			(size 0.3048 0.381)
			(layers "B.Cu" "B.Mask" "B.Paste")
			(net "P0V9_CPU1_RT0_2A_2D")
		)
		(pad "2" smd rect
			(at -0.2667 0 270)
			(size 0.3048 0.381)
			(layers "B.Cu" "B.Mask" "B.Paste")
			(net "GND")
		)
	)
	(footprint ""
		(layer "B.Cu")
		(at 130.657092 -50.302922 90)
		(property "Reference" "R6067"
			(at 0 0 90)
			(layer "B.SilkS")
			(hide yes)
			(effects
				(font
					(size 1.27 1.27)
				)
				(justify mirror)
			)
		)
		(property "Value" ""
			(at 0 0 90)
			(layer "B.Fab")
			(effects
				(font
					(size 1.27 1.27)
				)
				(justify mirror)
			)
		)
		(duplicate_pad_numbers_are_jumpers no)
		(fp_line
			(start 0.7874 -0.4064)
			(end -0.7874 -0.4064)
			(stroke
				(width 0.1524)
				(type default)
			)
			(layer "B.SilkS")
		)
		(fp_line
			(start -0.7874 -0.4064)
			(end -0.7874 0.4064)
			(stroke
				(width 0.1524)
				(type default)
			)
			(layer "B.SilkS")
		)
		(fp_line
			(start 0.7874 0.4064)
			(end 0.7874 -0.4064)
			(stroke
				(width 0.1524)
				(type default)
			)
			(layer "B.SilkS")
		)
		(fp_line
			(start -0.7874 0.4064)
			(end 0.7874 0.4064)
			(stroke
				(width 0.1524)
				(type default)
			)
			(layer "B.SilkS")
		)
		(fp_line
			(start 0.67945 -0.305054)
			(end 0.12065 -0.305054)
			(stroke
				(width 0.1)
				(type default)
			)
			(layer "B.Fab")
		)
		(fp_line
			(start 0.12065 -0.305054)
			(end 0.12065 -0.2794)
			(stroke
				(width 0.1)
				(type default)
			)
			(layer "B.Fab")
		)
		(fp_line
			(start -0.12065 -0.3048)
			(end -0.67945 -0.3048)
			(stroke
				(width 0.1)
				(type default)
			)
			(layer "B.Fab")
		)
		(fp_line
			(start -0.67945 -0.3048)
			(end -0.67945 0.3048)
			(stroke
				(width 0.1)
				(type default)
			)
			(layer "B.Fab")
		)
		(fp_line
			(start 0.12065 -0.2794)
			(end -0.12065 -0.2794)
			(stroke
				(width 0.1)
				(type default)
			)
			(layer "B.Fab")
		)
		(fp_line
			(start -0.12065 -0.2794)
			(end -0.12065 -0.3048)
			(stroke
				(width 0.1)
				(type default)
			)
			(layer "B.Fab")
		)
		(fp_line
			(start 0.12065 0.2794)
			(end 0.12065 0.3048)
			(stroke
				(width 0.1)
				(type default)
			)
			(layer "B.Fab")
		)
		(fp_line
			(start -0.120396 0.2794)
			(end 0.12065 0.2794)
			(stroke
				(width 0.1)
				(type default)
			)
			(layer "B.Fab")
		)
		(fp_line
			(start 0.67945 0.3048)
			(end 0.67945 -0.305054)
			(stroke
				(width 0.1)
				(type default)
			)
			(layer "B.Fab")
		)
		(fp_line
			(start 0.12065 0.3048)
			(end 0.67945 0.3048)
			(stroke
				(width 0.1)
				(type default)
			)
			(layer "B.Fab")
		)
		(fp_line
			(start -0.120396 0.3048)
			(end -0.120396 0.2794)
			(stroke
				(width 0.1)
				(type default)
			)
			(layer "B.Fab")
		)
		(fp_line
			(start -0.67945 0.3048)
			(end -0.120396 0.3048)
			(stroke
				(width 0.1)
				(type default)
			)
			(layer "B.Fab")
		)
		(pad "1" smd rect
			(at 0.40005 0 90)
			(size 0.4572 0.508)
			(layers "B.Cu" "B.Mask" "B.Paste")
			(net "JTAG_SCM_TDO_R")
		)
		(pad "2" smd rect
			(at -0.40005 0 90)
			(size 0.4572 0.508)
			(layers "B.Cu" "B.Mask" "B.Paste")
			(net "JTAG_SCM_TDI")
		)
	)
)
